# S9S_MB_2U (Grand Teton) — schematic netlist excerpt (pin names and nets, part order shuffled) for the footprints in the layout excerpt that follows; sources: Cadence DE-HDL packaged netlist, KiCad conversion of 03242023_DA0F0TMBIJ0_F0T_Motherboard_J_brd_V01_OCP.brd

C1366  Q_CAP  22UF 4V 20% X6S  pkg C0402  page 80 : A = PVNN_MAIN_CPU1 ; B = GND
R2481  Q_RES  4.75K 1% EMPTY  pkg 0402LF  page 208 : A = P3V3_AUX ; B = CLK_CK440_SMB_ADDR1

(kicad_pcb
	(version 20260206)
	(generator "pcbnew")
	(generator_version "10.0")
	(general
		(thickness 1.6)
		(legacy_teardrops no)
	)
	(paper "A4")
	(title_block
		(title "03242023_DA0F0TMBIJ0_F0T_Motherboard_J_brd_V01_OCP.brd")
		(comment 1 "Grand Teton / footprints 4572-4573 of 6105")
	)
	(layers
		(0 "F.Cu" signal "TOP")
		(4 "In1.Cu" signal "GND")
		(6 "In2.Cu" signal "IN1")
		(8 "In3.Cu" signal "GND1")
		(10 "In4.Cu" signal "IN2")
		(12 "In5.Cu" signal "GND2")
		(14 "In6.Cu" signal "IN3")
		(16 "In7.Cu" signal "GND3")
		(18 "In8.Cu" signal "VCC")
		(20 "In9.Cu" signal "VCC1")
		(22 "In10.Cu" signal "GND4")
		(24 "In11.Cu" signal "IN4")
		(26 "In12.Cu" signal "GND5")
		(28 "In13.Cu" signal "IN5")
		(30 "In14.Cu" signal "GND6")
		(32 "In15.Cu" signal "IN6")
		(34 "In16.Cu" signal "GND7")
		(2 "B.Cu" signal "BOTTOM")
		(9 "F.Adhes" user "F.Adhesive")
		(11 "B.Adhes" user "B.Adhesive")
		(13 "F.Paste" user "Package Geometry/Pastemask Top")
		(15 "B.Paste" user "Package Geometry/Pastemask Bottom")
		(5 "F.SilkS" user "Ref Des/Silkscreen Top")
		(7 "B.SilkS" user "Ref Des/Silkscreen Bottom")
		(1 "F.Mask" user "Board Geometry/Soldermask Top")
		(3 "B.Mask" user "Board Geometry/Soldermask Bottom")
		(17 "Dwgs.User" user "User.Drawings")
		(19 "Cmts.User" user "User.Comments")
		(21 "Eco1.User" user "User.Eco1")
		(23 "Eco2.User" user "User.Eco2")
		(25 "Edge.Cuts" user "Board Geometry/Outline")
		(27 "Margin" user)
		(31 "F.CrtYd" user "Package Geometry/Place Bound Top")
		(29 "B.CrtYd" user "Package Geometry/Place Bound Bottom")
		(35 "F.Fab" user "Ref Des/Assembly Top")
		(33 "B.Fab" user "Ref Des/Assembly Bottom")
	)
	(footprint ""
		(layer "B.Cu")
		(at 36.791392 -176.52238 180)
		(property "Reference" "C1366"
			(at 0 0 0)
			(layer "B.SilkS")
			(hide yes)
			(effects
				(font
					(size 1.27 1.27)
				)
				(justify mirror)
			)
		)
		(property "Value" ""
			(at 0 0 0)
			(layer "B.Fab")
			(effects
				(font
					(size 1.27 1.27)
				)
				(justify mirror)
			)
		)
		(duplicate_pad_numbers_are_jumpers no)
		(fp_line
			(start 0.7874 0.4064)
			(end 0.7874 -0.4064)
			(stroke
				(width 0.1524)
				(type default)
			)
			(layer "B.SilkS")
		)
		(fp_line
			(start 0.7874 -0.4064)
			(end -0.7874 -0.4064)
			(stroke
				(width 0.1524)
				(type default)
			)
			(layer "B.SilkS")
		)
		(fp_line
			(start -0.7874 0.4064)
			(end 0.7874 0.4064)
			(stroke
				(width 0.1524)
				(type default)
			)
			(layer "B.SilkS")
		)
		(fp_line
			(start -0.7874 -0.4064)
			(end -0.7874 0.4064)
			(stroke
				(width 0.1524)
				(type default)
			)
			(layer "B.SilkS")
		)
		(fp_line
			(start 0.67945 0.3048)
			(end 0.67945 -0.305054)
			(stroke
				(width 0.1)
				(type default)
			)
			(layer "B.Fab")
		)
		(fp_line
			(start 0.67945 -0.305054)
			(end 0.12065 -0.305054)
			(stroke
				(width 0.1)
				(type default)
			)
			(layer "B.Fab")
		)
		(fp_line
			(start 0.12065 0.3048)
			(end 0.67945 0.3048)
			(stroke
				(width 0.1)
				(type default)
			)
			(layer "B.Fab")
		)
		(fp_line
			(start 0.12065 0.2794)
			(end 0.12065 0.3048)
			(stroke
				(width 0.1)
				(type default)
			)
			(layer "B.Fab")
		)
		(fp_line
			(start 0.12065 -0.2794)
			(end -0.12065 -0.2794)
			(stroke
				(width 0.1)
				(type default)
			)
			(layer "B.Fab")
		)
		(fp_line
			(start 0.12065 -0.305054)
			(end 0.12065 -0.2794)
			(stroke
				(width 0.1)
				(type default)
			)
			(layer "B.Fab")
		)
		(fp_line
			(start -0.120396 0.3048)
			(end -0.120396 0.2794)
			(stroke
				(width 0.1)
				(type default)
			)
			(layer "B.Fab")
		)
		(fp_line
			(start -0.120396 0.2794)
			(end 0.12065 0.2794)
			(stroke
				(width 0.1)
				(type default)
			)
			(layer "B.Fab")
		)
		(fp_line
			(start -0.12065 -0.2794)
			(end -0.12065 -0.3048)
			(stroke
				(width 0.1)
				(type default)
			)
			(layer "B.Fab")
		)
		(fp_line
			(start -0.12065 -0.3048)
			(end -0.67945 -0.3048)
			(stroke
				(width 0.1)
				(type default)
			)
			(layer "B.Fab")
		)
		(fp_line
			(start -0.67945 0.3048)
			(end -0.120396 0.3048)
			(stroke
				(width 0.1)
				(type default)
			)
			(layer "B.Fab")
		)
		(fp_line
			(start -0.67945 -0.3048)
			(end -0.67945 0.3048)
			(stroke
				(width 0.1)
				(type default)
			)
			(layer "B.Fab")
		)
		(pad "1" smd circle
			(at 0.40005 0)
			(size 0 0)
			(layers "B.Cu" "B.Mask" "B.Paste")
			(net "PVNN_MAIN_CPU1")
		)
		(pad "2" smd circle
			(at -0.40005 0)
			(size 0 0)
			(layers "B.Cu" "B.Mask" "B.Paste")
			(net "GND")
		)
	)
	(footprint ""
		(layer "B.Cu")
		(at 245.835424 -101.127052 180)
		(property "Reference" "R2481"
			(at 0 0 0)
			(layer "B.SilkS")
			(hide yes)
			(effects
				(font
					(size 1.27 1.27)
				)
				(justify mirror)
			)
		)
		(property "Value" ""
			(at 0 0 0)
			(layer "B.Fab")
			(effects
				(font
					(size 1.27 1.27)
				)
				(justify mirror)
			)
		)
		(duplicate_pad_numbers_are_jumpers no)
		(fp_line
			(start 0.7874 0.4064)
			(end 0.7874 -0.4064)
			(stroke
				(width 0.1524)
				(type default)
			)
			(layer "B.SilkS")
		)
		(fp_line
			(start 0.7874 -0.4064)
			(end -0.7874 -0.4064)
			(stroke
				(width 0.1524)
				(type default)
			)
			(layer "B.SilkS")
		)
		(fp_line
			(start -0.7874 0.4064)
			(end 0.7874 0.4064)
			(stroke
				(width 0.1524)
				(type default)
			)
			(layer "B.SilkS")
		)
		(fp_line
			(start -0.7874 -0.4064)
			(end -0.7874 0.4064)
			(stroke
				(width 0.1524)
				(type default)
			)
			(layer "B.SilkS")
		)
		(fp_line
			(start 0.67945 0.3048)
			(end 0.67945 -0.305054)
			(stroke
				(width 0.1)
				(type default)
			)
			(layer "B.Fab")
		)
		(fp_line
			(start 0.67945 -0.305054)
			(end 0.12065 -0.305054)
			(stroke
				(width 0.1)
				(type default)
			)
			(layer "B.Fab")
		)
		(fp_line
			(start 0.12065 0.3048)
			(end 0.67945 0.3048)
			(stroke
				(width 0.1)
				(type default)
			)
			(layer "B.Fab")
		)
		(fp_line
			(start 0.12065 0.2794)
			(end 0.12065 0.3048)
			(stroke
				(width 0.1)
				(type default)
			)
			(layer "B.Fab")
		)
		(fp_line
			(start 0.12065 -0.2794)
			(end -0.12065 -0.2794)
			(stroke
				(width 0.1)
				(type default)
			)
			(layer "B.Fab")
		)
		(fp_line
			(start 0.12065 -0.305054)
			(end 0.12065 -0.2794)
			(stroke
				(width 0.1)
				(type default)
			)
			(layer "B.Fab")
		)
		(fp_line
			(start -0.120396 0.3048)
			(end -0.120396 0.2794)
			(stroke
				(width 0.1)
				(type default)
			)
			(layer "B.Fab")
		)
		(fp_line
			(start -0.120396 0.2794)
			(end 0.12065 0.2794)
			(stroke
				(width 0.1)
				(type default)
			)
			(layer "B.Fab")
		)
		(fp_line
			(start -0.12065 -0.2794)
			(end -0.12065 -0.3048)
			(stroke
				(width 0.1)
				(type default)
			)
			(layer "B.Fab")
		)
		(fp_line
			(start -0.12065 -0.3048)
			(end -0.67945 -0.3048)
			(stroke
				(width 0.1)
				(type default)
			)
			(layer "B.Fab")
		)
		(fp_line
			(start -0.67945 0.3048)
			(end -0.120396 0.3048)
			(stroke
				(width 0.1)
				(type default)
			)
			(layer "B.Fab")
		)
		(fp_line
			(start -0.67945 -0.3048)
			(end -0.67945 0.3048)
			(stroke
				(width 0.1)
				(type default)
			)
			(layer "B.Fab")
		)
		(pad "1" smd circle
			(at 0.40005 0)
			(size 0 0)
			(layers "B.Cu" "B.Mask" "B.Paste")
			(net "P3V3_AUX")
		)
		(pad "2" smd circle
			(at -0.40005 0)
			(size 0 0)
			(layers "B.Cu" "B.Mask" "B.Paste")
			(net "CLK_CK440_SMB_ADDR1")
		)
	)
)
